# S9S_MB_2U (Grand Teton) — schematic netlist excerpt (pin names and nets, part order shuffled) for the footprints in the layout excerpt that follows; sources: Cadence DE-HDL packaged netlist, KiCad conversion of 03242023_DA0F0TMBIJ0_F0T_Motherboard_J_brd_V01_OCP.brd

C139  Q_CAP_DIFFBUS  DIFF BUS_0.22UF 6.3V 20% X6S  pkg C0201  page 178 : \1\ = DMI_CPU0_PCH_TX_C_DN<7> ; \2\ = DMI_CPU0_PCH_TX_DN<7>
PR3828  Q_RES  15K 1% EMPTY  pkg 0402LF  page 162 : A = P12V_OCP_OV_2 ; B = GND
C843  Q_CAP_DIFFBUS  DIFF BUS_0.22UF 6.3V 20% X6S  pkg C0201  page 174 : \1\ = P5E_CPU0_PE1_TX_C_DP<13> ; \2\ = P5E_CPU0_PE1_TX_DP<13>

(kicad_pcb
	(version 20260206)
	(generator "pcbnew")
	(generator_version "10.0")
	(general
		(thickness 1.6)
		(legacy_teardrops no)
	)
	(paper "A4")
	(title_block
		(title "03242023_DA0F0TMBIJ0_F0T_Motherboard_J_brd_V01_OCP.brd")
		(comment 1 "Grand Teton / footprints 2218-2220 of 6105")
	)
	(layers
		(0 "F.Cu" signal "TOP")
		(4 "In1.Cu" signal "GND")
		(6 "In2.Cu" signal "IN1")
		(8 "In3.Cu" signal "GND1")
		(10 "In4.Cu" signal "IN2")
		(12 "In5.Cu" signal "GND2")
		(14 "In6.Cu" signal "IN3")
		(16 "In7.Cu" signal "GND3")
		(18 "In8.Cu" signal "VCC")
		(20 "In9.Cu" signal "VCC1")
		(22 "In10.Cu" signal "GND4")
		(24 "In11.Cu" signal "IN4")
		(26 "In12.Cu" signal "GND5")
		(28 "In13.Cu" signal "IN5")
		(30 "In14.Cu" signal "GND6")
		(32 "In15.Cu" signal "IN6")
		(34 "In16.Cu" signal "GND7")
		(2 "B.Cu" signal "BOTTOM")
		(9 "F.Adhes" user "F.Adhesive")
		(11 "B.Adhes" user "B.Adhesive")
		(13 "F.Paste" user "Package Geometry/Pastemask Top")
		(15 "B.Paste" user "Package Geometry/Pastemask Bottom")
		(5 "F.SilkS" user "Ref Des/Silkscreen Top")
		(7 "B.SilkS" user "Ref Des/Silkscreen Bottom")
		(1 "F.Mask" user "Board Geometry/Soldermask Top")
		(3 "B.Mask" user "Board Geometry/Soldermask Bottom")
		(17 "Dwgs.User" user "User.Drawings")
		(19 "Cmts.User" user "User.Comments")
		(21 "Eco1.User" user "User.Eco1")
		(23 "Eco2.User" user "User.Eco2")
		(25 "Edge.Cuts" user "Board Geometry/Outline")
		(27 "Margin" user)
		(31 "F.CrtYd" user "Package Geometry/Place Bound Top")
		(29 "B.CrtYd" user "Package Geometry/Place Bound Bottom")
		(35 "F.Fab" user "Ref Des/Assembly Top")
		(33 "B.Fab" user "Ref Des/Assembly Bottom")
	)
	(footprint ""
		(layer "F.Cu")
		(at 75.416918 -17.148302 180)
		(property "Reference" "PR3828"
			(at 0 0 180)
			(layer "F.SilkS")
			(hide yes)
			(effects
				(font
					(size 1.27 1.27)
				)
			)
		)
		(property "Value" ""
			(at 0 0 180)
			(layer "F.Fab")
			(effects
				(font
					(size 1.27 1.27)
				)
			)
		)
		(duplicate_pad_numbers_are_jumpers no)
		(fp_line
			(start 0.7874 0.4064)
			(end -0.7874 0.4064)
			(stroke
				(width 0.1524)
				(type default)
			)
			(layer "F.SilkS")
		)
		(fp_line
			(start 0.7874 -0.4064)
			(end 0.7874 0.4064)
			(stroke
				(width 0.1524)
				(type default)
			)
			(layer "F.SilkS")
		)
		(fp_line
			(start -0.7874 0.4064)
			(end -0.7874 -0.4064)
			(stroke
				(width 0.1524)
				(type default)
			)
			(layer "F.SilkS")
		)
		(fp_line
			(start -0.7874 -0.4064)
			(end 0.7874 -0.4064)
			(stroke
				(width 0.1524)
				(type default)
			)
			(layer "F.SilkS")
		)
		(fp_line
			(start 0.67945 0.3048)
			(end 0.120396 0.3048)
			(stroke
				(width 0.1)
				(type default)
			)
			(layer "F.Fab")
		)
		(fp_line
			(start 0.67945 -0.3048)
			(end 0.67945 0.3048)
			(stroke
				(width 0.1)
				(type default)
			)
			(layer "F.Fab")
		)
		(fp_line
			(start 0.12065 -0.2794)
			(end 0.12065 -0.3048)
			(stroke
				(width 0.1)
				(type default)
			)
			(layer "F.Fab")
		)
		(fp_line
			(start 0.12065 -0.3048)
			(end 0.67945 -0.3048)
			(stroke
				(width 0.1)
				(type default)
			)
			(layer "F.Fab")
		)
		(fp_line
			(start 0.120396 0.3048)
			(end 0.120396 0.2794)
			(stroke
				(width 0.1)
				(type default)
			)
			(layer "F.Fab")
		)
		(fp_line
			(start 0.120396 0.2794)
			(end -0.12065 0.2794)
			(stroke
				(width 0.1)
				(type default)
			)
			(layer "F.Fab")
		)
		(fp_line
			(start -0.12065 0.3048)
			(end -0.67945 0.3048)
			(stroke
				(width 0.1)
				(type default)
			)
			(layer "F.Fab")
		)
		(fp_line
			(start -0.12065 0.2794)
			(end -0.12065 0.3048)
			(stroke
				(width 0.1)
				(type default)
			)
			(layer "F.Fab")
		)
		(fp_line
			(start -0.12065 -0.2794)
			(end 0.12065 -0.2794)
			(stroke
				(width 0.1)
				(type default)
			)
			(layer "F.Fab")
		)
		(fp_line
			(start -0.12065 -0.305054)
			(end -0.12065 -0.2794)
			(stroke
				(width 0.1)
				(type default)
			)
			(layer "F.Fab")
		)
		(fp_line
			(start -0.67945 0.3048)
			(end -0.67945 -0.305054)
			(stroke
				(width 0.1)
				(type default)
			)
			(layer "F.Fab")
		)
		(fp_line
			(start -0.67945 -0.305054)
			(end -0.12065 -0.305054)
			(stroke
				(width 0.1)
				(type default)
			)
			(layer "F.Fab")
		)
		(pad "1" smd circle
			(at -0.40005 0 180)
			(size 0 0)
			(layers "F.Cu" "F.Mask" "F.Paste")
			(net "P12V_OCP_OV_2")
		)
		(pad "2" smd circle
			(at 0.40005 0 180)
			(size 0 0)
			(layers "F.Cu" "F.Mask" "F.Paste")
			(net "GND")
		)
	)
	(footprint ""
		(layer "F.Cu")
		(at 395.603984 -16.088614 90)
		(property "Reference" "C843"
			(at 0 0 90)
			(layer "F.SilkS")
			(hide yes)
			(effects
				(font
					(size 1.27 1.27)
				)
			)
		)
		(property "Value" ""
			(at 0 0 90)
			(layer "F.Fab")
			(effects
				(font
					(size 1.27 1.27)
				)
			)
		)
		(duplicate_pad_numbers_are_jumpers no)
		(fp_line
			(start 0.299974 -0.150114)
			(end 0.299974 0.150114)
			(stroke
				(width 0.1)
				(type default)
			)
			(layer "F.Fab")
		)
		(fp_line
			(start -0.299974 -0.150114)
			(end 0.299974 -0.150114)
			(stroke
				(width 0.1)
				(type default)
			)
			(layer "F.Fab")
		)
		(fp_line
			(start 0.299974 0.150114)
			(end -0.299974 0.150114)
			(stroke
				(width 0.1)
				(type default)
			)
			(layer "F.Fab")
		)
		(fp_line
			(start -0.299974 0.150114)
			(end -0.299974 -0.150114)
			(stroke
				(width 0.1)
				(type default)
			)
			(layer "F.Fab")
		)
		(pad "1" smd rect
			(at -0.2667 0 90)
			(size 0.3048 0.381)
			(layers "F.Cu" "F.Mask" "F.Paste")
			(net "P5E_CPU0_PE1_TX_C_DP<13>")
		)
		(pad "2" smd rect
			(at 0.2667 0 90)
			(size 0.3048 0.381)
			(layers "F.Cu" "F.Mask" "F.Paste")
			(net "P5E_CPU0_PE1_TX_DP<13>")
		)
	)
	(footprint ""
		(layer "F.Cu")
		(at 350.691196 -60.591954)
		(property "Reference" "C139"
			(at 0 0 0)
			(layer "F.SilkS")
			(hide yes)
			(effects
				(font
					(size 1.27 1.27)
				)
			)
		)
		(property "Value" ""
			(at 0 0 0)
			(layer "F.Fab")
			(effects
				(font
					(size 1.27 1.27)
				)
			)
		)
		(duplicate_pad_numbers_are_jumpers no)
		(fp_line
			(start -0.299974 -0.150114)
			(end 0.299974 -0.150114)
			(stroke
				(width 0.1)
				(type default)
			)
			(layer "F.Fab")
		)
		(fp_line
			(start -0.299974 0.150114)
			(end -0.299974 -0.150114)
			(stroke
				(width 0.1)
				(type default)
			)
			(layer "F.Fab")
		)
		(fp_line
			(start 0.299974 -0.150114)
			(end 0.299974 0.150114)
			(stroke
				(width 0.1)
				(type default)
			)
			(layer "F.Fab")
		)
		(fp_line
			(start 0.299974 0.150114)
			(end -0.299974 0.150114)
			(stroke
				(width 0.1)
				(type default)
			)
			(layer "F.Fab")
		)
		(pad "1" smd rect
			(at -0.2667 0)
			(size 0.3048 0.381)
			(layers "F.Cu" "F.Mask" "F.Paste")
			(net "DMI_CPU0_PCH_TX_C_DN<7>")
		)
		(pad "2" smd rect
			(at 0.2667 0)
			(size 0.3048 0.381)
			(layers "F.Cu" "F.Mask" "F.Paste")
			(net "DMI_CPU0_PCH_TX_DN<7>")
		)
		(zone
			(layer "In1.Cu")
			(hatch none 0.5)
			(connect_pads
				(clearance 0)
			)
			(min_thickness 0.25)
			(keepout
				(tracks not_allowed)
				(vias allowed)
				(pads allowed)
				(copperpour not_allowed)
				(footprints allowed)
			)
			(placement
				(enabled no)
				(sheetname "")
			)
			(fill
				(thermal_gap 0.5)
				(thermal_bridge_width 0.5)
				(island_removal_mode 0)
			)
			(polygon
				(pts
					(arc
						(start 350.297496 -60.350654)
						(mid 350.243614 -60.372972)
						(end 350.221296 -60.426854)
					)
					(arc
						(start 350.221296 -60.757054)
						(mid 350.243614 -60.810936)
						(end 350.297496 -60.833254)
					)
					(arc
						(start 350.551496 -60.833254)
						(mid 350.605378 -60.810936)
						(end 350.627696 -60.757054)
					)
					(arc
						(start 350.627696 -60.426854)
						(mid 350.605378 -60.372972)
						(end 350.551496 -60.350654)
					)
				)
			)
		)
		(zone
			(layer "In1.Cu")
			(hatch none 0.5)
			(connect_pads
				(clearance 0)
			)
			(min_thickness 0.25)
			(keepout
				(tracks not_allowed)
				(vias allowed)
				(pads allowed)
				(copperpour not_allowed)
				(footprints allowed)
			)
			(placement
				(enabled no)
				(sheetname "")
			)
			(fill
				(thermal_gap 0.5)
				(thermal_bridge_width 0.5)
				(island_removal_mode 0)
			)
			(polygon
				(pts
					(arc
						(start 350.830896 -60.350654)
						(mid 350.777014 -60.372972)
						(end 350.754696 -60.426854)
					)
					(arc
						(start 350.754696 -60.757054)
						(mid 350.777014 -60.810936)
						(end 350.830896 -60.833254)
					)
					(arc
						(start 351.084896 -60.833254)
						(mid 351.138778 -60.810936)
						(end 351.161096 -60.757054)
					)
					(arc
						(start 351.161096 -60.426854)
						(mid 351.138778 -60.372972)
						(end 351.084896 -60.350654)
					)
				)
			)
		)
	)
)
